(kicad_pcb
	(version 20260206)
	(generator "pcbnew")
	(generator_version "10.0")
	(general
		(thickness 1.6)
		(legacy_teardrops no)
	)
	(paper "A4")
	(title_block
		(title "04192023_DAF0TMB3IC0_F0TG_MB_C_brd_V02_OCP.brd")
		(comment 1 "Grand Teton / footprints 1195-1202 of 8354")
	)
	(layers
		(0 "F.Cu" signal "TOP")
		(4 "In1.Cu" signal "GND")
		(6 "In2.Cu" signal "IN1")
		(8 "In3.Cu" signal "GND1")
		(10 "In4.Cu" signal "IN2")
		(12 "In5.Cu" signal "GND2")
		(14 "In6.Cu" signal "IN3")
		(16 "In7.Cu" signal "GND3")
		(18 "In8.Cu" signal "VCC")
		(20 "In9.Cu" signal "VCC1")
		(22 "In10.Cu" signal "GND4")
		(24 "In11.Cu" signal "IN4")
		(26 "In12.Cu" signal "GND5")
		(28 "In13.Cu" signal "IN5")
		(30 "In14.Cu" signal "GND6")
		(32 "In15.Cu" signal "IN6")
		(34 "In16.Cu" signal "GND7")
		(2 "B.Cu" signal "BOTTOM")
		(9 "F.Adhes" user "F.Adhesive")
		(11 "B.Adhes" user "B.Adhesive")
		(13 "F.Paste" user "Package Geometry/Pastemask Top")
		(15 "B.Paste" user "Package Geometry/Pastemask Bottom")
		(5 "F.SilkS" user "Ref Des/Silkscreen Top")
		(7 "B.SilkS" user "Ref Des/Silkscreen Bottom")
		(1 "F.Mask" user "Board Geometry/Soldermask Top")
		(3 "B.Mask" user "Board Geometry/Soldermask Bottom")
		(17 "Dwgs.User" user "User.Drawings")
		(19 "Cmts.User" user "User.Comments")
		(21 "Eco1.User" user "User.Eco1")
		(23 "Eco2.User" user "User.Eco2")
		(25 "Edge.Cuts" user "Board Geometry/Outline")
		(27 "Margin" user)
		(31 "F.CrtYd" user "Package Geometry/Place Bound Top")
		(29 "B.CrtYd" user "Package Geometry/Place Bound Bottom")
		(35 "F.Fab" user "Ref Des/Assembly Top")
		(33 "B.Fab" user "Ref Des/Assembly Bottom")
	)
	(footprint ""
		(layer "F.Cu")
		(at 44.623228 -399.41246)
		(property "Reference" "R6704"
			(at 0 0 0)
			(layer "F.SilkS")
			(hide yes)
			(effects
				(font
					(size 1.27 1.27)
				)
			)
		)
		(property "Value" ""
			(at 0 0 0)
			(layer "F.Fab")
			(effects
				(font
					(size 1.27 1.27)
				)
			)
		)
		(duplicate_pad_numbers_are_jumpers no)
		(fp_line
			(start -1.2954 -0.5842)
			(end 1.2954 -0.5842)
			(stroke
				(width 0.1524)
				(type default)
			)
			(layer "F.SilkS")
		)
		(fp_line
			(start -1.2954 0.5842)
			(end -1.2954 -0.5842)
			(stroke
				(width 0.1524)
				(type default)
			)
			(layer "F.SilkS")
		)
		(fp_line
			(start 1.2954 -0.5842)
			(end 1.2954 0.5842)
			(stroke
				(width 0.1524)
				(type default)
			)
			(layer "F.SilkS")
		)
		(fp_line
			(start 1.2954 0.5842)
			(end -1.2954 0.5842)
			(stroke
				(width 0.1524)
				(type default)
			)
			(layer "F.SilkS")
		)
		(fp_line
			(start -1.1938 -0.406654)
			(end -0.8636 -0.406654)
			(stroke
				(width 0.1)
				(type default)
			)
			(layer "F.Fab")
		)
		(fp_line
			(start -1.1938 0.4064)
			(end -1.1938 -0.406654)
			(stroke
				(width 0.1)
				(type default)
			)
			(layer "F.Fab")
		)
		(fp_line
			(start -0.8636 -0.4572)
			(end 0.8636 -0.4572)
			(stroke
				(width 0.1)
				(type default)
			)
			(layer "F.Fab")
		)
		(fp_line
			(start -0.8636 -0.406654)
			(end -0.8636 -0.4572)
			(stroke
				(width 0.1)
				(type default)
			)
			(layer "F.Fab")
		)
		(fp_line
			(start -0.8636 0.4064)
			(end -1.1938 0.4064)
			(stroke
				(width 0.1)
				(type default)
			)
			(layer "F.Fab")
		)
		(fp_line
			(start -0.8636 0.4318)
			(end -0.8636 0.4064)
			(stroke
				(width 0.1)
				(type default)
			)
			(layer "F.Fab")
		)
		(fp_line
			(start -0.8636 0.4572)
			(end -0.8636 0.4318)
			(stroke
				(width 0.1)
				(type default)
			)
			(layer "F.Fab")
		)
		(fp_line
			(start 0.8636 -0.4572)
			(end 0.8636 -0.406654)
			(stroke
				(width 0.1)
				(type default)
			)
			(layer "F.Fab")
		)
		(fp_line
			(start 0.8636 -0.406654)
			(end 1.1938 -0.406654)
			(stroke
				(width 0.1)
				(type default)
			)
			(layer "F.Fab")
		)
		(fp_line
			(start 0.8636 0.4064)
			(end 0.8636 0.4572)
			(stroke
				(width 0.1)
				(type default)
			)
			(layer "F.Fab")
		)
		(fp_line
			(start 0.8636 0.4572)
			(end -0.8636 0.4572)
			(stroke
				(width 0.1)
				(type default)
			)
			(layer "F.Fab")
		)
		(fp_line
			(start 1.1938 -0.406654)
			(end 1.1938 0.4064)
			(stroke
				(width 0.1)
				(type default)
			)
			(layer "F.Fab")
		)
		(fp_line
			(start 1.1938 0.4064)
			(end 0.8636 0.4064)
			(stroke
				(width 0.1)
				(type default)
			)
			(layer "F.Fab")
		)
		(pad "1" smd rect
			(at -0.7366 0 270)
			(size 0.7112 0.8128)
			(layers "F.Cu" "F.Mask" "F.Paste")
			(net "P0V9_CPU1_RT_2D")
		)
		(pad "2" smd rect
			(at 0.7366 0 270)
			(size 0.7112 0.8128)
			(layers "F.Cu" "F.Mask" "F.Paste")
			(net "P0V9_CPU1_RT0_2A_2D")
		)
	)
	(footprint ""
		(layer "F.Cu")
		(at 337.464146 -416.899344 -90)
		(property "Reference" "C6524"
			(at 0 0 270)
			(layer "F.SilkS")
			(hide yes)
			(effects
				(font
					(size 1.27 1.27)
				)
			)
		)
		(property "Value" ""
			(at 0 0 270)
			(layer "F.Fab")
			(effects
				(font
					(size 1.27 1.27)
				)
			)
		)
		(duplicate_pad_numbers_are_jumpers no)
		(fp_line
			(start -0.299974 0.150114)
			(end -0.299974 -0.150114)
			(stroke
				(width 0.1)
				(type default)
			)
			(layer "F.Fab")
		)
		(fp_line
			(start 0.299974 0.150114)
			(end -0.299974 0.150114)
			(stroke
				(width 0.1)
				(type default)
			)
			(layer "F.Fab")
		)
		(fp_line
			(start -0.299974 -0.150114)
			(end 0.299974 -0.150114)
			(stroke
				(width 0.1)
				(type default)
			)
			(layer "F.Fab")
		)
		(fp_line
			(start 0.299974 -0.150114)
			(end 0.299974 0.150114)
			(stroke
				(width 0.1)
				(type default)
			)
			(layer "F.Fab")
		)
		(pad "1" smd rect
			(at -0.2667 0 270)
			(size 0.3048 0.381)
			(layers "F.Cu" "F.Mask" "F.Paste")
			(net "P5E_CPU0_P0_TX_BUF_C_DN<11>")
		)
		(pad "2" smd rect
			(at 0.2667 0 270)
			(size 0.3048 0.381)
			(layers "F.Cu" "F.Mask" "F.Paste")
			(net "P5E_CPU0_P0_TX_BUF_DN<11>")
		)
	)
	(footprint ""
		(layer "F.Cu")
		(at 201.047604 -34.923984 90)
		(property "Reference" "R3635"
			(at 5.299456 -1.945132 0)
			(unlocked yes)
			(layer "F.SilkS")
			(effects
				(font
					(size 0.7874 0.5842)
					(thickness 0.1524)
				)
				(justify left)
			)
		)
		(property "Value" ""
			(at 0 0 90)
			(layer "F.Fab")
			(effects
				(font
					(size 1.27 1.27)
				)
			)
		)
		(duplicate_pad_numbers_are_jumpers no)
		(fp_line
			(start 3.937508 -1.8796)
			(end -3.937508 -1.8796)
			(stroke
				(width 0.1524)
				(type default)
			)
			(layer "F.SilkS")
		)
		(fp_line
			(start -3.937508 -1.8796)
			(end -3.937508 1.8796)
			(stroke
				(width 0.1524)
				(type default)
			)
			(layer "F.SilkS")
		)
		(fp_line
			(start 3.937508 1.8796)
			(end 3.937508 -1.8796)
			(stroke
				(width 0.1524)
				(type default)
			)
			(layer "F.SilkS")
		)
		(fp_line
			(start -3.937508 1.8796)
			(end 3.937508 1.8796)
			(stroke
				(width 0.1524)
				(type default)
			)
			(layer "F.SilkS")
		)
		(fp_line
			(start 3.275076 -1.674876)
			(end -3.275076 -1.674876)
			(stroke
				(width 0.1)
				(type default)
			)
			(layer "F.Fab")
		)
		(fp_line
			(start -3.275076 -1.674876)
			(end -3.275076 1.674876)
			(stroke
				(width 0.1)
				(type default)
			)
			(layer "F.Fab")
		)
		(fp_line
			(start 3.275076 1.674876)
			(end 3.275076 -1.674876)
			(stroke
				(width 0.1)
				(type default)
			)
			(layer "F.Fab")
		)
		(fp_line
			(start -3.275076 1.674876)
			(end 3.275076 1.674876)
			(stroke
				(width 0.1)
				(type default)
			)
			(layer "F.Fab")
		)
		(pad "1" smd rect
			(at -2.350008 0 90)
			(size 2.921 3.5052)
			(layers "F.Cu" "F.Mask" "F.Paste")
			(net "P12V_SCM")
		)
		(pad "2" smd rect
			(at 2.350008 0 90)
			(size 2.921 3.5052)
			(layers "F.Cu" "F.Mask" "F.Paste")
			(net "P12V_SCM_R")
		)
	)
	(footprint ""
		(layer "F.Cu")
		(at 379.704092 -381.41783 -90)
		(property "Reference" "C885"
			(at 0 0 270)
			(layer "F.SilkS")
			(hide yes)
			(effects
				(font
					(size 1.27 1.27)
				)
			)
		)
		(property "Value" ""
			(at 0 0 270)
			(layer "F.Fab")
			(effects
				(font
					(size 1.27 1.27)
				)
			)
		)
		(duplicate_pad_numbers_are_jumpers no)
		(fp_line
			(start -0.299974 0.150114)
			(end -0.299974 -0.150114)
			(stroke
				(width 0.1)
				(type default)
			)
			(layer "F.Fab")
		)
		(fp_line
			(start 0.299974 0.150114)
			(end -0.299974 0.150114)
			(stroke
				(width 0.1)
				(type default)
			)
			(layer "F.Fab")
		)
		(fp_line
			(start -0.299974 -0.150114)
			(end 0.299974 -0.150114)
			(stroke
				(width 0.1)
				(type default)
			)
			(layer "F.Fab")
		)
		(fp_line
			(start 0.299974 -0.150114)
			(end 0.299974 0.150114)
			(stroke
				(width 0.1)
				(type default)
			)
			(layer "F.Fab")
		)
		(pad "1" smd rect
			(at -0.2667 0 270)
			(size 0.3048 0.381)
			(layers "F.Cu" "F.Mask" "F.Paste")
			(net "P5E_CPU0_P3_TX_C_DP<8>")
		)
		(pad "2" smd rect
			(at 0.2667 0 270)
			(size 0.3048 0.381)
			(layers "F.Cu" "F.Mask" "F.Paste")
			(net "P5E_CPU0_P3_TX_DP<8>")
		)
	)
	(footprint ""
		(layer "F.Cu")
		(at 160.06953 -352.668078 -90)
		(property "Reference" "R8381"
			(at 0 0 270)
			(layer "F.SilkS")
			(hide yes)
			(effects
				(font
					(size 1.27 1.27)
				)
			)
		)
		(property "Value" ""
			(at 0 0 270)
			(layer "F.Fab")
			(effects
				(font
					(size 1.27 1.27)
				)
			)
		)
		(duplicate_pad_numbers_are_jumpers no)
		(fp_line
			(start -0.7874 0.4064)
			(end -0.7874 -0.4064)
			(stroke
				(width 0.1524)
				(type default)
			)
			(layer "F.SilkS")
		)
		(fp_line
			(start 0.7874 0.4064)
			(end -0.7874 0.4064)
			(stroke
				(width 0.1524)
				(type default)
			)
			(layer "F.SilkS")
		)
		(fp_line
			(start -0.7874 -0.4064)
			(end 0.7874 -0.4064)
			(stroke
				(width 0.1524)
				(type default)
			)
			(layer "F.SilkS")
		)
		(fp_line
			(start 0.7874 -0.4064)
			(end 0.7874 0.4064)
			(stroke
				(width 0.1524)
				(type default)
			)
			(layer "F.SilkS")
		)
		(fp_line
			(start -0.67945 0.3048)
			(end -0.67945 -0.305054)
			(stroke
				(width 0.1)
				(type default)
			)
			(layer "F.Fab")
		)
		(fp_line
			(start -0.12065 0.3048)
			(end -0.67945 0.3048)
			(stroke
				(width 0.1)
				(type default)
			)
			(layer "F.Fab")
		)
		(fp_line
			(start 0.120396 0.3048)
			(end 0.120396 0.2794)
			(stroke
				(width 0.1)
				(type default)
			)
			(layer "F.Fab")
		)
		(fp_line
			(start 0.67945 0.3048)
			(end 0.120396 0.3048)
			(stroke
				(width 0.1)
				(type default)
			)
			(layer "F.Fab")
		)
		(fp_line
			(start -0.12065 0.2794)
			(end -0.12065 0.3048)
			(stroke
				(width 0.1)
				(type default)
			)
			(layer "F.Fab")
		)
		(fp_line
			(start 0.120396 0.2794)
			(end -0.12065 0.2794)
			(stroke
				(width 0.1)
				(type default)
			)
			(layer "F.Fab")
		)
		(fp_line
			(start -0.12065 -0.2794)
			(end 0.12065 -0.2794)
			(stroke
				(width 0.1)
				(type default)
			)
			(layer "F.Fab")
		)
		(fp_line
			(start 0.12065 -0.2794)
			(end 0.12065 -0.3048)
			(stroke
				(width 0.1)
				(type default)
			)
			(layer "F.Fab")
		)
		(fp_line
			(start 0.12065 -0.3048)
			(end 0.67945 -0.3048)
			(stroke
				(width 0.1)
				(type default)
			)
			(layer "F.Fab")
		)
		(fp_line
			(start 0.67945 -0.3048)
			(end 0.67945 0.3048)
			(stroke
				(width 0.1)
				(type default)
			)
			(layer "F.Fab")
		)
		(fp_line
			(start -0.67945 -0.305054)
			(end -0.12065 -0.305054)
			(stroke
				(width 0.1)
				(type default)
			)
			(layer "F.Fab")
		)
		(fp_line
			(start -0.12065 -0.305054)
			(end -0.12065 -0.2794)
			(stroke
				(width 0.1)
				(type default)
			)
			(layer "F.Fab")
		)
		(pad "1" smd circle
			(at -0.40005 0 270)
			(size 0 0)
			(layers "F.Cu" "F.Mask" "F.Paste")
			(net "SMB_SCM_2_R2_SCL")
		)
		(pad "2" smd circle
			(at 0.40005 0 270)
			(size 0 0)
			(layers "F.Cu" "F.Mask" "F.Paste")
			(net "PVDD11_S3_P1_PMSCL_R")
		)
	)
	(footprint ""
		(layer "F.Cu")
		(at 77.638148 -179.360068 -90)
		(property "Reference" "PR46"
			(at 0 0 270)
			(layer "F.SilkS")
			(hide yes)
			(effects
				(font
					(size 1.27 1.27)
				)
			)
		)
		(property "Value" ""
			(at 0 0 270)
			(layer "F.Fab")
			(effects
				(font
					(size 1.27 1.27)
				)
			)
		)
		(duplicate_pad_numbers_are_jumpers no)
		(fp_line
			(start -0.7874 0.4064)
			(end -0.7874 -0.4064)
			(stroke
				(width 0.1524)
				(type default)
			)
			(layer "F.SilkS")
		)
		(fp_line
			(start 0.7874 0.4064)
			(end -0.7874 0.4064)
			(stroke
				(width 0.1524)
				(type default)
			)
			(layer "F.SilkS")
		)
		(fp_line
			(start -0.7874 -0.4064)
			(end 0.7874 -0.4064)
			(stroke
				(width 0.1524)
				(type default)
			)
			(layer "F.SilkS")
		)
		(fp_line
			(start 0.7874 -0.4064)
			(end 0.7874 0.4064)
			(stroke
				(width 0.1524)
				(type default)
			)
			(layer "F.SilkS")
		)
		(fp_line
			(start -0.67945 0.3048)
			(end -0.67945 -0.305054)
			(stroke
				(width 0.1)
				(type default)
			)
			(layer "F.Fab")
		)
		(fp_line
			(start -0.12065 0.3048)
			(end -0.67945 0.3048)
			(stroke
				(width 0.1)
				(type default)
			)
			(layer "F.Fab")
		)
		(fp_line
			(start 0.120396 0.3048)
			(end 0.120396 0.2794)
			(stroke
				(width 0.1)
				(type default)
			)
			(layer "F.Fab")
		)
		(fp_line
			(start 0.67945 0.3048)
			(end 0.120396 0.3048)
			(stroke
				(width 0.1)
				(type default)
			)
			(layer "F.Fab")
		)
		(fp_line
			(start -0.12065 0.2794)
			(end -0.12065 0.3048)
			(stroke
				(width 0.1)
				(type default)
			)
			(layer "F.Fab")
		)
		(fp_line
			(start 0.120396 0.2794)
			(end -0.12065 0.2794)
			(stroke
				(width 0.1)
				(type default)
			)
			(layer "F.Fab")
		)
		(fp_line
			(start -0.12065 -0.2794)
			(end 0.12065 -0.2794)
			(stroke
				(width 0.1)
				(type default)
			)
			(layer "F.Fab")
		)
		(fp_line
			(start 0.12065 -0.2794)
			(end 0.12065 -0.3048)
			(stroke
				(width 0.1)
				(type default)
			)
			(layer "F.Fab")
		)
		(fp_line
			(start 0.12065 -0.3048)
			(end 0.67945 -0.3048)
			(stroke
				(width 0.1)
				(type default)
			)
			(layer "F.Fab")
		)
		(fp_line
			(start 0.67945 -0.3048)
			(end 0.67945 0.3048)
			(stroke
				(width 0.1)
				(type default)
			)
			(layer "F.Fab")
		)
		(fp_line
			(start -0.67945 -0.305054)
			(end -0.12065 -0.305054)
			(stroke
				(width 0.1)
				(type default)
			)
			(layer "F.Fab")
		)
		(fp_line
			(start -0.12065 -0.305054)
			(end -0.12065 -0.2794)
			(stroke
				(width 0.1)
				(type default)
			)
			(layer "F.Fab")
		)
		(pad "1" smd circle
			(at -0.40005 0 270)
			(size 0 0)
			(layers "F.Cu" "F.Mask" "F.Paste")
			(net "SW_PVDDCR_CPU0_P1_SW5_RC")
		)
		(pad "2" smd circle
			(at 0.40005 0 270)
			(size 0 0)
			(layers "F.Cu" "F.Mask" "F.Paste")
			(net "GND")
		)
	)
	(footprint ""
		(layer "F.Cu")
		(at 372.557294 -192.061084 180)
		(property "Reference" "PL52"
			(at 4.468876 2.638806 90)
			(unlocked yes)
			(layer "F.SilkS")
			(effects
				(font
					(size 0.7874 0.5842)
					(thickness 0.1524)
				)
				(justify left)
			)
		)
		(property "Value" ""
			(at 0 0 180)
			(layer "F.Fab")
			(effects
				(font
					(size 1.27 1.27)
				)
			)
		)
		(duplicate_pad_numbers_are_jumpers no)
		(fp_line
			(start 3.750056 5.500116)
			(end 3.750056 -5.500116)
			(stroke
				(width 0.1524)
				(type default)
			)
			(layer "F.SilkS")
		)
		(fp_line
			(start 3.750056 -5.500116)
			(end 2.393442 -5.500116)
			(stroke
				(width 0.1524)
				(type default)
			)
			(layer "F.SilkS")
		)
		(fp_line
			(start 2.393442 5.500116)
			(end 3.750056 5.500116)
			(stroke
				(width 0.1524)
				(type default)
			)
			(layer "F.SilkS")
		)
		(fp_line
			(start -2.393442 5.500116)
			(end -3.750056 5.500116)
			(stroke
				(width 0.1524)
				(type default)
			)
			(layer "F.SilkS")
		)
		(fp_line
			(start -3.750056 5.500116)
			(end -3.750056 -5.500116)
			(stroke
				(width 0.1524)
				(type default)
			)
			(layer "F.SilkS")
		)
		(fp_line
			(start -3.750056 -5.500116)
			(end -2.393442 -5.500116)
			(stroke
				(width 0.1524)
				(type default)
			)
			(layer "F.SilkS")
		)
		(fp_poly
			(pts
				(xy -3.9116 -4.249928) (xy -4.505706 -3.952748) (xy -4.505706 -4.547108)
			)
			(stroke
				(width 0)
				(type default)
			)
			(fill yes)
			(layer "F.SilkS")
		)
		(fp_line
			(start 3.750056 5.500116)
			(end 3.750056 -5.500116)
			(stroke
				(width 0.1)
				(type default)
			)
			(layer "F.Fab")
		)
		(fp_line
			(start 3.750056 -5.500116)
			(end -3.750056 -5.500116)
			(stroke
				(width 0.1)
				(type default)
			)
			(layer "F.Fab")
		)
		(fp_line
			(start -3.750056 5.500116)
			(end 3.750056 5.500116)
			(stroke
				(width 0.1)
				(type default)
			)
			(layer "F.Fab")
		)
		(fp_line
			(start -3.750056 -5.500116)
			(end -3.750056 5.500116)
			(stroke
				(width 0.1)
				(type default)
			)
			(layer "F.Fab")
		)
		(fp_poly
			(pts
				(xy -4.9276 -4.757928) (xy -4.9276 -3.741928) (xy -3.9116 -4.249928)
			)
			(stroke
				(width 0)
				(type default)
			)
			(fill yes)
			(layer "F.Fab")
		)
		(pad "1" smd rect
			(at 0 -4.249928 90)
			(size 2.413 4.5212)
			(layers "F.Cu" "F.Mask" "F.Paste")
			(net "SW_PVDDCR_CPU0_P0_SW2")
		)
		(pad "2" smd rect
			(at 0 -1.175004 90)
			(size 1.3716 4.5212)
			(layers "F.Cu" "F.Mask" "F.Paste")
			(net "IND_CPU0_P0_CPL1")
		)
		(pad "3" smd rect
			(at 0 1.175004 90)
			(size 1.3716 4.5212)
			(layers "F.Cu" "F.Mask" "F.Paste")
			(net "IND_CPU0_P0_CPL2")
		)
		(pad "4" smd rect
			(at 0 4.249928 90)
			(size 2.413 4.5212)
			(layers "F.Cu" "F.Mask" "F.Paste")
			(net "PVDDCR_CPU0_P0")
		)
	)
	(footprint ""
		(layer "F.Cu")
		(at 142.595092 -382.39446 180)
		(property "Reference" "C773"
			(at 0 0 180)
			(layer "F.SilkS")
			(hide yes)
			(effects
				(font
					(size 1.27 1.27)
				)
			)
		)
		(property "Value" ""
			(at 0 0 180)
			(layer "F.Fab")
			(effects
				(font
					(size 1.27 1.27)
				)
			)
		)
		(duplicate_pad_numbers_are_jumpers no)
		(fp_line
			(start 0.299974 0.150114)
			(end -0.299974 0.150114)
			(stroke
				(width 0.1)
				(type default)
			)
			(layer "F.Fab")
		)
		(fp_line
			(start 0.299974 -0.150114)
			(end 0.299974 0.150114)
			(stroke
				(width 0.1)
				(type default)
			)
			(layer "F.Fab")
		)
		(fp_line
			(start -0.299974 0.150114)
			(end -0.299974 -0.150114)
			(stroke
				(width 0.1)
				(type default)
			)
			(layer "F.Fab")
		)
		(fp_line
			(start -0.299974 -0.150114)
			(end 0.299974 -0.150114)
			(stroke
				(width 0.1)
				(type default)
			)
			(layer "F.Fab")
		)
		(pad "1" smd rect
			(at -0.2667 0 180)
			(size 0.3048 0.381)
			(layers "F.Cu" "F.Mask" "F.Paste")
			(net "P5E_CPU1_P2_TX_C_DP<0>")
		)
		(pad "2" smd rect
			(at 0.2667 0 180)
			(size 0.3048 0.381)
			(layers "F.Cu" "F.Mask" "F.Paste")
			(net "P5E_CPU1_P2_TX_DP<0>")
		)
	)
)
